(kicad_pcb
	(version 20260206)
	(generator "pcbnew")
	(generator_version "10.0")
	(general
		(thickness 1.6)
		(legacy_teardrops no)
	)
	(paper "A4")
	(title_block
		(title "panther-plus-userver — 13130-1b_20150205.brd")
		(comment 1 "Honey Badger (Wiwynn) / footprint 894 of 1509 (DIMM1), pads 142-148 of 210")
	)
	(layers
		(0 "F.Cu" signal "TOP")
		(4 "In1.Cu" signal "L2")
		(6 "In2.Cu" signal "L3")
		(8 "In3.Cu" signal "L4")
		(10 "In4.Cu" signal "L5")
		(12 "In5.Cu" signal "L6")
		(14 "In6.Cu" signal "L7")
		(16 "In7.Cu" signal "L8")
		(18 "In8.Cu" signal "L9")
		(20 "In9.Cu" signal "L10")
		(22 "In10.Cu" signal "L11")
		(2 "B.Cu" signal "BOTTOM")
		(9 "F.Adhes" user "F.Adhesive")
		(11 "B.Adhes" user "B.Adhesive")
		(13 "F.Paste" user "Package Geometry/Pastemask Top")
		(15 "B.Paste" user "Package Geometry/Pastemask Bottom")
		(5 "F.SilkS" user "Ref Des/Silkscreen Top")
		(7 "B.SilkS" user "Ref Des/Silkscreen Bottom")
		(1 "F.Mask" user "Board Geometry/Soldermask Top")
		(3 "B.Mask" user "Board Geometry/Soldermask Bottom")
		(17 "Dwgs.User" user "User.Drawings")
		(19 "Cmts.User" user "User.Comments")
		(21 "Eco1.User" user "User.Eco1")
		(23 "Eco2.User" user "User.Eco2")
		(25 "Edge.Cuts" user "Board Geometry/Outline")
		(27 "Margin" user)
		(31 "F.CrtYd" user "Package Geometry/Place Bound Top")
		(29 "B.CrtYd" user "Package Geometry/Place Bound Bottom")
		(35 "F.Fab" user "Ref Des/Assembly Top")
		(33 "B.Fab" user "Ref Des/Assembly Bottom")
	)
	(footprint ""
		(layer "B.Cu")
		(at 158.500064 -66.699892 180)
		(property "Reference" "DIMM1"
			(at 0 0 0)
			(layer "B.SilkS")
			(hide yes)
			(effects
				(font
					(size 1.27 1.27)
				)
				(justify mirror)
			)
		)
		(property "Value" "DDR3-204P-142-COLAY-1-GP-U"
			(at 41.312338 -16.676878 180)
			(unlocked yes)
			(layer "B.Fab")
			(hide yes)
			(effects
				(font
					(size 1.016 1.016)
					(thickness 0.1524)
				)
				(justify mirror)
			)
		)
		(property "Device Type" "AS0A626-J8R6-7H-COLAY-1"
			(at 41.312338 -18.200878 180)
			(unlocked yes)
			(layer "B.Fab")
			(hide yes)
			(effects
				(font
					(size 1.016 1.016)
					(thickness 0.1524)
				)
				(justify mirror)
			)
		)
		(duplicate_pad_numbers_are_jumpers no)
		(pad "140" smd custom
			(at 12.450064 4.100068)
			(size 0.1143 0.1143)
			(layers "B.Cu" "B.Mask" "B.Paste")
			(net "GND")
			(options
				(clearance outline)
				(anchor circle)
			)
			(primitives
				(gr_poly
					(pts
						(xy 0 -0.9017) (xy -0.03175 -0.89916) (xy -0.0635 -0.889) (xy -0.09144 -0.87376) (xy -0.11684 -0.85344)
						(xy -0.13716 -0.82804) (xy -0.1524 -0.8001) (xy -0.16256 -0.76835) (xy -0.1651 -0.7366) (xy -0.1651 -0.11938)
						(xy -0.17272 -0.11176) (xy -0.19812 -0.0762) (xy -0.2032 -0.06604) (xy -0.20701 -0.05715) (xy -0.21209 -0.04699)
						(xy -0.2159 -0.03683) (xy -0.21844 -0.02667) (xy -0.22225 -0.01524) (xy -0.22352 -0.00508) (xy -0.22606 0.00508)
						(xy -0.22733 0.01651) (xy -0.22733 0.02667) (xy -0.2286 0.0381) (xy -0.22733 0.04953) (xy -0.22733 0.05969)
						(xy -0.22606 0.07112) (xy -0.22352 0.08128) (xy -0.22225 0.09144) (xy -0.21844 0.10287) (xy -0.2159 0.11303)
						(xy -0.21209 0.12319) (xy -0.20701 0.13335) (xy -0.2032 0.14224) (xy -0.19812 0.1524) (xy -0.17272 0.18796)
						(xy -0.1651 0.19558) (xy -0.1651 0.7366) (xy -0.16256 0.76835) (xy -0.1524 0.8001) (xy -0.13716 0.82804)
						(xy -0.11684 0.85344) (xy -0.09144 0.87376) (xy -0.0635 0.889) (xy -0.03175 0.89916) (xy 0 0.9017)
						(xy 0.03175 0.89916) (xy 0.0635 0.889) (xy 0.09144 0.87376) (xy 0.11684 0.85344) (xy 0.13716 0.82804)
						(xy 0.1524 0.8001) (xy 0.16256 0.76835) (xy 0.1651 0.7366) (xy 0.1651 0.19685) (xy 0.17272 0.18923)
						(xy 0.17907 0.18034) (xy 0.18669 0.17145) (xy 0.19177 0.16256) (xy 0.19812 0.15367) (xy 0.20828 0.13335)
						(xy 0.21971 0.10287) (xy 0.22225 0.09271) (xy 0.22479 0.08128) (xy 0.22606 0.07112) (xy 0.2286 0.05969)
						(xy 0.2286 0.01651) (xy 0.22606 0.00508) (xy 0.22479 -0.00508) (xy 0.22225 -0.01651) (xy 0.21971 -0.02667)
						(xy 0.20828 -0.05715) (xy 0.19812 -0.07747) (xy 0.19177 -0.08636) (xy 0.18669 -0.09525) (xy 0.17907 -0.10414)
						(xy 0.17272 -0.11303) (xy 0.1651 -0.12065) (xy 0.1651 -0.7366) (xy 0.16256 -0.76835) (xy 0.1524 -0.8001)
						(xy 0.13716 -0.82804) (xy 0.11684 -0.85344) (xy 0.09144 -0.87376) (xy 0.0635 -0.889) (xy 0.03175 -0.89916)
					)
					(width 0)
					(fill yes)
				)
			)
		)
		(pad "141" smd custom
			(at 12.750038 -4.100068)
			(size 0.1143 0.1143)
			(layers "B.Cu" "B.Mask" "B.Paste")
			(net "M_A_DQS_DP4")
			(options
				(clearance outline)
				(anchor circle)
			)
			(primitives
				(gr_poly
					(pts
						(xy 0 -0.9017) (xy -0.03175 -0.89916) (xy -0.0635 -0.889) (xy -0.09144 -0.87376) (xy -0.11684 -0.85344)
						(xy -0.13716 -0.82804) (xy -0.1524 -0.8001) (xy -0.16256 -0.76835) (xy -0.1651 -0.7366) (xy -0.1651 -0.44958)
						(xy -0.17272 -0.44196) (xy -0.19812 -0.4064) (xy -0.2032 -0.39624) (xy -0.20701 -0.38735) (xy -0.21209 -0.37719)
						(xy -0.2159 -0.36703) (xy -0.21844 -0.35687) (xy -0.22225 -0.34544) (xy -0.22352 -0.33528) (xy -0.22606 -0.32512)
						(xy -0.22733 -0.31369) (xy -0.22733 -0.30353) (xy -0.2286 -0.2921) (xy -0.22733 -0.28067) (xy -0.22733 -0.27051)
						(xy -0.22606 -0.25908) (xy -0.22352 -0.24892) (xy -0.22225 -0.23876) (xy -0.21844 -0.22733) (xy -0.2159 -0.21717)
						(xy -0.21209 -0.20701) (xy -0.20701 -0.19685) (xy -0.2032 -0.18796) (xy -0.19812 -0.1778) (xy -0.17272 -0.14224)
						(xy -0.1651 -0.13462) (xy -0.1651 0.7366) (xy -0.16256 0.76835) (xy -0.1524 0.8001) (xy -0.13716 0.82804)
						(xy -0.11684 0.85344) (xy -0.09144 0.87376) (xy -0.0635 0.889) (xy -0.03175 0.89916) (xy 0 0.9017)
						(xy 0.03175 0.89916) (xy 0.0635 0.889) (xy 0.09144 0.87376) (xy 0.11684 0.85344) (xy 0.13716 0.82804)
						(xy 0.1524 0.8001) (xy 0.16256 0.76835) (xy 0.1651 0.7366) (xy 0.1651 -0.13462) (xy 0.17272 -0.14224)
						(xy 0.19812 -0.1778) (xy 0.2032 -0.18796) (xy 0.20701 -0.19685) (xy 0.21209 -0.20701) (xy 0.2159 -0.21717)
						(xy 0.21844 -0.22733) (xy 0.22225 -0.23876) (xy 0.22352 -0.24892) (xy 0.22606 -0.25908) (xy 0.22733 -0.27051)
						(xy 0.22733 -0.28067) (xy 0.2286 -0.2921) (xy 0.22733 -0.30353) (xy 0.22733 -0.31369) (xy 0.22606 -0.32512)
						(xy 0.22352 -0.33528) (xy 0.22225 -0.34544) (xy 0.21844 -0.35687) (xy 0.2159 -0.36703) (xy 0.21209 -0.37719)
						(xy 0.20701 -0.38735) (xy 0.2032 -0.39624) (xy 0.19812 -0.4064) (xy 0.17272 -0.44196) (xy 0.1651 -0.44958)
						(xy 0.1651 -0.7366) (xy 0.16256 -0.76835) (xy 0.1524 -0.8001) (xy 0.13716 -0.82804) (xy 0.11684 -0.85344)
						(xy 0.09144 -0.87376) (xy 0.0635 -0.889) (xy 0.03175 -0.89916)
					)
					(width 0)
					(fill yes)
				)
			)
		)
		(pad "142" smd custom
			(at 13.050012 4.100068)
			(size 0.1143 0.1143)
			(layers "B.Cu" "B.Mask" "B.Paste")
			(net "M_A_DQ38")
			(options
				(clearance outline)
				(anchor circle)
			)
			(primitives
				(gr_poly
					(pts
						(xy 0 -0.9017) (xy -0.03175 -0.89916) (xy -0.0635 -0.889) (xy -0.09144 -0.87376) (xy -0.11684 -0.85344)
						(xy -0.13716 -0.82804) (xy -0.1524 -0.8001) (xy -0.16256 -0.76835) (xy -0.1651 -0.7366) (xy -0.1651 0.13462)
						(xy -0.17272 0.14224) (xy -0.19812 0.1778) (xy -0.2032 0.18796) (xy -0.20701 0.19685) (xy -0.21209 0.20701)
						(xy -0.2159 0.21717) (xy -0.21844 0.22733) (xy -0.22225 0.23876) (xy -0.22352 0.24892) (xy -0.22606 0.25908)
						(xy -0.22733 0.27051) (xy -0.22733 0.28067) (xy -0.2286 0.2921) (xy -0.22733 0.30353) (xy -0.22733 0.31369)
						(xy -0.22606 0.32512) (xy -0.22352 0.33528) (xy -0.22225 0.34544) (xy -0.21844 0.35687) (xy -0.2159 0.36703)
						(xy -0.21209 0.37719) (xy -0.20701 0.38735) (xy -0.2032 0.39624) (xy -0.19812 0.4064) (xy -0.17272 0.44196)
						(xy -0.1651 0.44958) (xy -0.1651 0.7366) (xy -0.16256 0.76835) (xy -0.1524 0.8001) (xy -0.13716 0.82804)
						(xy -0.11684 0.85344) (xy -0.09144 0.87376) (xy -0.0635 0.889) (xy -0.03175 0.89916) (xy 0 0.9017)
						(xy 0.03175 0.89916) (xy 0.0635 0.889) (xy 0.09144 0.87376) (xy 0.11684 0.85344) (xy 0.13716 0.82804)
						(xy 0.1524 0.8001) (xy 0.16256 0.76835) (xy 0.1651 0.7366) (xy 0.1651 0.44958) (xy 0.17272 0.44196)
						(xy 0.19812 0.4064) (xy 0.2032 0.39624) (xy 0.20701 0.38735) (xy 0.21209 0.37719) (xy 0.2159 0.36703)
						(xy 0.21844 0.35687) (xy 0.22225 0.34544) (xy 0.22352 0.33528) (xy 0.22606 0.32512) (xy 0.22733 0.31369)
						(xy 0.22733 0.30353) (xy 0.2286 0.2921) (xy 0.22733 0.28067) (xy 0.22733 0.27051) (xy 0.22606 0.25908)
						(xy 0.22352 0.24892) (xy 0.22225 0.23876) (xy 0.21844 0.22733) (xy 0.2159 0.21717) (xy 0.21209 0.20701)
						(xy 0.20701 0.19685) (xy 0.2032 0.18796) (xy 0.19812 0.1778) (xy 0.17272 0.14224) (xy 0.1651 0.13462)
						(xy 0.1651 -0.7366) (xy 0.16256 -0.76835) (xy 0.1524 -0.8001) (xy 0.13716 -0.82804) (xy 0.11684 -0.85344)
						(xy 0.09144 -0.87376) (xy 0.0635 -0.889) (xy 0.03175 -0.89916)
					)
					(width 0)
					(fill yes)
				)
			)
		)
		(pad "143" smd custom
			(at 13.349986 -4.100068)
			(size 0.1143 0.1143)
			(layers "B.Cu" "B.Mask" "B.Paste")
			(net "GND")
			(options
				(clearance outline)
				(anchor circle)
			)
			(primitives
				(gr_poly
					(pts
						(xy 0 -0.9017) (xy -0.03175 -0.89916) (xy -0.0635 -0.889) (xy -0.09144 -0.87376) (xy -0.11684 -0.85344)
						(xy -0.13716 -0.82804) (xy -0.1524 -0.8001) (xy -0.16256 -0.76835) (xy -0.1651 -0.7366) (xy -0.1651 -0.19685)
						(xy -0.17272 -0.18923) (xy -0.17907 -0.18034) (xy -0.18669 -0.17145) (xy -0.19177 -0.16256) (xy -0.19812 -0.15367)
						(xy -0.20828 -0.13335) (xy -0.21971 -0.10287) (xy -0.22225 -0.09271) (xy -0.22479 -0.08128) (xy -0.22606 -0.07112)
						(xy -0.2286 -0.05969) (xy -0.2286 -0.01651) (xy -0.22606 -0.00508) (xy -0.22479 0.00508) (xy -0.22225 0.01651)
						(xy -0.21971 0.02667) (xy -0.20828 0.05715) (xy -0.19812 0.07747) (xy -0.19177 0.08636) (xy -0.18669 0.09525)
						(xy -0.17907 0.10414) (xy -0.17272 0.11303) (xy -0.1651 0.12065) (xy -0.1651 0.7366) (xy -0.16256 0.76835)
						(xy -0.1524 0.8001) (xy -0.13716 0.82804) (xy -0.11684 0.85344) (xy -0.09144 0.87376) (xy -0.0635 0.889)
						(xy -0.03175 0.89916) (xy 0 0.9017) (xy 0.03175 0.89916) (xy 0.0635 0.889) (xy 0.09144 0.87376)
						(xy 0.11684 0.85344) (xy 0.13716 0.82804) (xy 0.1524 0.8001) (xy 0.16256 0.76835) (xy 0.1651 0.7366)
						(xy 0.1651 0.11938) (xy 0.17272 0.11176) (xy 0.19812 0.0762) (xy 0.2032 0.06604) (xy 0.20701 0.05715)
						(xy 0.21209 0.04699) (xy 0.2159 0.03683) (xy 0.21844 0.02667) (xy 0.22225 0.01524) (xy 0.22352 0.00508)
						(xy 0.22606 -0.00508) (xy 0.22733 -0.01651) (xy 0.22733 -0.02667) (xy 0.2286 -0.0381) (xy 0.22733 -0.04953)
						(xy 0.22733 -0.05969) (xy 0.22606 -0.07112) (xy 0.22352 -0.08128) (xy 0.22225 -0.09144) (xy 0.21844 -0.10287)
						(xy 0.2159 -0.11303) (xy 0.21209 -0.12319) (xy 0.20701 -0.13335) (xy 0.2032 -0.14224) (xy 0.19812 -0.1524)
						(xy 0.17272 -0.18796) (xy 0.1651 -0.19558) (xy 0.1651 -0.7366) (xy 0.16256 -0.76835) (xy 0.1524 -0.8001)
						(xy 0.13716 -0.82804) (xy 0.11684 -0.85344) (xy 0.09144 -0.87376) (xy 0.0635 -0.889) (xy 0.03175 -0.89916)
					)
					(width 0)
					(fill yes)
				)
			)
		)
		(pad "144" smd custom
			(at 13.64996 4.100068)
			(size 0.1143 0.1143)
			(layers "B.Cu" "B.Mask" "B.Paste")
			(net "M_A_DQ39")
			(options
				(clearance outline)
				(anchor circle)
			)
			(primitives
				(gr_poly
					(pts
						(xy 0 -0.9017) (xy -0.03175 -0.89916) (xy -0.0635 -0.889) (xy -0.09144 -0.87376) (xy -0.11684 -0.85344)
						(xy -0.13716 -0.82804) (xy -0.1524 -0.8001) (xy -0.16256 -0.76835) (xy -0.1651 -0.7366) (xy -0.1651 -0.11938)
						(xy -0.17272 -0.11176) (xy -0.19812 -0.0762) (xy -0.2032 -0.06604) (xy -0.20701 -0.05715) (xy -0.21209 -0.04699)
						(xy -0.2159 -0.03683) (xy -0.21844 -0.02667) (xy -0.22225 -0.01524) (xy -0.22352 -0.00508) (xy -0.22606 0.00508)
						(xy -0.22733 0.01651) (xy -0.22733 0.02667) (xy -0.2286 0.0381) (xy -0.22733 0.04953) (xy -0.22733 0.05969)
						(xy -0.22606 0.07112) (xy -0.22352 0.08128) (xy -0.22225 0.09144) (xy -0.21844 0.10287) (xy -0.2159 0.11303)
						(xy -0.21209 0.12319) (xy -0.20701 0.13335) (xy -0.2032 0.14224) (xy -0.19812 0.1524) (xy -0.17272 0.18796)
						(xy -0.1651 0.19558) (xy -0.1651 0.7366) (xy -0.16256 0.76835) (xy -0.1524 0.8001) (xy -0.13716 0.82804)
						(xy -0.11684 0.85344) (xy -0.09144 0.87376) (xy -0.0635 0.889) (xy -0.03175 0.89916) (xy 0 0.9017)
						(xy 0.03175 0.89916) (xy 0.0635 0.889) (xy 0.09144 0.87376) (xy 0.11684 0.85344) (xy 0.13716 0.82804)
						(xy 0.1524 0.8001) (xy 0.16256 0.76835) (xy 0.1651 0.7366) (xy 0.1651 0.19685) (xy 0.17272 0.18923)
						(xy 0.17907 0.18034) (xy 0.18669 0.17145) (xy 0.19177 0.16256) (xy 0.19812 0.15367) (xy 0.20828 0.13335)
						(xy 0.21971 0.10287) (xy 0.22225 0.09271) (xy 0.22479 0.08128) (xy 0.22606 0.07112) (xy 0.2286 0.05969)
						(xy 0.2286 0.01651) (xy 0.22606 0.00508) (xy 0.22479 -0.00508) (xy 0.22225 -0.01651) (xy 0.21971 -0.02667)
						(xy 0.20828 -0.05715) (xy 0.19812 -0.07747) (xy 0.19177 -0.08636) (xy 0.18669 -0.09525) (xy 0.17907 -0.10414)
						(xy 0.17272 -0.11303) (xy 0.1651 -0.12065) (xy 0.1651 -0.7366) (xy 0.16256 -0.76835) (xy 0.1524 -0.8001)
						(xy 0.13716 -0.82804) (xy 0.11684 -0.85344) (xy 0.09144 -0.87376) (xy 0.0635 -0.889) (xy 0.03175 -0.89916)
					)
					(width 0)
					(fill yes)
				)
			)
		)
		(pad "145" smd custom
			(at 13.949934 -4.100068)
			(size 0.1143 0.1143)
			(layers "B.Cu" "B.Mask" "B.Paste")
			(net "M_A_DQ34")
			(options
				(clearance outline)
				(anchor circle)
			)
			(primitives
				(gr_poly
					(pts
						(xy 0 -0.9017) (xy -0.03175 -0.89916) (xy -0.0635 -0.889) (xy -0.09144 -0.87376) (xy -0.11684 -0.85344)
						(xy -0.13716 -0.82804) (xy -0.1524 -0.8001) (xy -0.16256 -0.76835) (xy -0.1651 -0.7366) (xy -0.1651 -0.44958)
						(xy -0.17272 -0.44196) (xy -0.19812 -0.4064) (xy -0.2032 -0.39624) (xy -0.20701 -0.38735) (xy -0.21209 -0.37719)
						(xy -0.2159 -0.36703) (xy -0.21844 -0.35687) (xy -0.22225 -0.34544) (xy -0.22352 -0.33528) (xy -0.22606 -0.32512)
						(xy -0.22733 -0.31369) (xy -0.22733 -0.30353) (xy -0.2286 -0.2921) (xy -0.22733 -0.28067) (xy -0.22733 -0.27051)
						(xy -0.22606 -0.25908) (xy -0.22352 -0.24892) (xy -0.22225 -0.23876) (xy -0.21844 -0.22733) (xy -0.2159 -0.21717)
						(xy -0.21209 -0.20701) (xy -0.20701 -0.19685) (xy -0.2032 -0.18796) (xy -0.19812 -0.1778) (xy -0.17272 -0.14224)
						(xy -0.1651 -0.13462) (xy -0.1651 0.7366) (xy -0.16256 0.76835) (xy -0.1524 0.8001) (xy -0.13716 0.82804)
						(xy -0.11684 0.85344) (xy -0.09144 0.87376) (xy -0.0635 0.889) (xy -0.03175 0.89916) (xy 0 0.9017)
						(xy 0.03175 0.89916) (xy 0.0635 0.889) (xy 0.09144 0.87376) (xy 0.11684 0.85344) (xy 0.13716 0.82804)
						(xy 0.1524 0.8001) (xy 0.16256 0.76835) (xy 0.1651 0.7366) (xy 0.1651 -0.13462) (xy 0.17272 -0.14224)
						(xy 0.19812 -0.1778) (xy 0.2032 -0.18796) (xy 0.20701 -0.19685) (xy 0.21209 -0.20701) (xy 0.2159 -0.21717)
						(xy 0.21844 -0.22733) (xy 0.22225 -0.23876) (xy 0.22352 -0.24892) (xy 0.22606 -0.25908) (xy 0.22733 -0.27051)
						(xy 0.22733 -0.28067) (xy 0.2286 -0.2921) (xy 0.22733 -0.30353) (xy 0.22733 -0.31369) (xy 0.22606 -0.32512)
						(xy 0.22352 -0.33528) (xy 0.22225 -0.34544) (xy 0.21844 -0.35687) (xy 0.2159 -0.36703) (xy 0.21209 -0.37719)
						(xy 0.20701 -0.38735) (xy 0.2032 -0.39624) (xy 0.19812 -0.4064) (xy 0.17272 -0.44196) (xy 0.1651 -0.44958)
						(xy 0.1651 -0.7366) (xy 0.16256 -0.76835) (xy 0.1524 -0.8001) (xy 0.13716 -0.82804) (xy 0.11684 -0.85344)
						(xy 0.09144 -0.87376) (xy 0.0635 -0.889) (xy 0.03175 -0.89916)
					)
					(width 0)
					(fill yes)
				)
			)
		)
		(pad "146" smd custom
			(at 14.249908 4.100068)
			(size 0.1143 0.1143)
			(layers "B.Cu" "B.Mask" "B.Paste")
			(net "GND")
			(options
				(clearance outline)
				(anchor circle)
			)
			(primitives
				(gr_poly
					(pts
						(xy 0 -0.9017) (xy -0.03175 -0.89916) (xy -0.0635 -0.889) (xy -0.09144 -0.87376) (xy -0.11684 -0.85344)
						(xy -0.13716 -0.82804) (xy -0.1524 -0.8001) (xy -0.16256 -0.76835) (xy -0.1651 -0.7366) (xy -0.1651 0.13462)
						(xy -0.17272 0.14224) (xy -0.19812 0.1778) (xy -0.2032 0.18796) (xy -0.20701 0.19685) (xy -0.21209 0.20701)
						(xy -0.2159 0.21717) (xy -0.21844 0.22733) (xy -0.22225 0.23876) (xy -0.22352 0.24892) (xy -0.22606 0.25908)
						(xy -0.22733 0.27051) (xy -0.22733 0.28067) (xy -0.2286 0.2921) (xy -0.22733 0.30353) (xy -0.22733 0.31369)
						(xy -0.22606 0.32512) (xy -0.22352 0.33528) (xy -0.22225 0.34544) (xy -0.21844 0.35687) (xy -0.2159 0.36703)
						(xy -0.21209 0.37719) (xy -0.20701 0.38735) (xy -0.2032 0.39624) (xy -0.19812 0.4064) (xy -0.17272 0.44196)
						(xy -0.1651 0.44958) (xy -0.1651 0.7366) (xy -0.16256 0.76835) (xy -0.1524 0.8001) (xy -0.13716 0.82804)
						(xy -0.11684 0.85344) (xy -0.09144 0.87376) (xy -0.0635 0.889) (xy -0.03175 0.89916) (xy 0 0.9017)
						(xy 0.03175 0.89916) (xy 0.0635 0.889) (xy 0.09144 0.87376) (xy 0.11684 0.85344) (xy 0.13716 0.82804)
						(xy 0.1524 0.8001) (xy 0.16256 0.76835) (xy 0.1651 0.7366) (xy 0.1651 0.44958) (xy 0.17272 0.44196)
						(xy 0.19812 0.4064) (xy 0.2032 0.39624) (xy 0.20701 0.38735) (xy 0.21209 0.37719) (xy 0.2159 0.36703)
						(xy 0.21844 0.35687) (xy 0.22225 0.34544) (xy 0.22352 0.33528) (xy 0.22606 0.32512) (xy 0.22733 0.31369)
						(xy 0.22733 0.30353) (xy 0.2286 0.2921) (xy 0.22733 0.28067) (xy 0.22733 0.27051) (xy 0.22606 0.25908)
						(xy 0.22352 0.24892) (xy 0.22225 0.23876) (xy 0.21844 0.22733) (xy 0.2159 0.21717) (xy 0.21209 0.20701)
						(xy 0.20701 0.19685) (xy 0.2032 0.18796) (xy 0.19812 0.1778) (xy 0.17272 0.14224) (xy 0.1651 0.13462)
						(xy 0.1651 -0.7366) (xy 0.16256 -0.76835) (xy 0.1524 -0.8001) (xy 0.13716 -0.82804) (xy 0.11684 -0.85344)
						(xy 0.09144 -0.87376) (xy 0.0635 -0.889) (xy 0.03175 -0.89916)
					)
					(width 0)
					(fill yes)
				)
			)
		)
	)
)
